# T6G (Grand Teton) — schematic netlist excerpt (pin names and nets, part order shuffled) for the footprints in the layout excerpt that follows; sources: Cadence DE-HDL packaged netlist, KiCad conversion of 04192023_DAF0TMB3IC0_F0TG_MB_C_brd_V02_OCP.brd

C399  Q_CAP  22UF 4V 20% X6S  pkg C0402  page 345 : A = P0V9_CPU1_RT2_2A ; B = GND
C7025  Q_CAP  100UF 4V 20% X6S  pkg C0805  page 334 : A = P0V9_CPU1_RT1_2A ; B = GND
R934  Q_RES  0 5% CHIP  pkg 0402LF  page 166 : A = FM_BIOS_POST_CMPLT_N ; B = BOOT_RDY_R1_N

(kicad_pcb
	(version 20260206)
	(generator "pcbnew")
	(generator_version "10.0")
	(general
		(thickness 1.6)
		(legacy_teardrops no)
	)
	(paper "A4")
	(title_block
		(title "04192023_DAF0TMB3IC0_F0TG_MB_C_brd_V02_OCP.brd")
		(comment 1 "Grand Teton / footprints 7782-7784 of 8354")
	)
	(layers
		(0 "F.Cu" signal "TOP")
		(4 "In1.Cu" signal "GND")
		(6 "In2.Cu" signal "IN1")
		(8 "In3.Cu" signal "GND1")
		(10 "In4.Cu" signal "IN2")
		(12 "In5.Cu" signal "GND2")
		(14 "In6.Cu" signal "IN3")
		(16 "In7.Cu" signal "GND3")
		(18 "In8.Cu" signal "VCC")
		(20 "In9.Cu" signal "VCC1")
		(22 "In10.Cu" signal "GND4")
		(24 "In11.Cu" signal "IN4")
		(26 "In12.Cu" signal "GND5")
		(28 "In13.Cu" signal "IN5")
		(30 "In14.Cu" signal "GND6")
		(32 "In15.Cu" signal "IN6")
		(34 "In16.Cu" signal "GND7")
		(2 "B.Cu" signal "BOTTOM")
		(9 "F.Adhes" user "F.Adhesive")
		(11 "B.Adhes" user "B.Adhesive")
		(13 "F.Paste" user "Package Geometry/Pastemask Top")
		(15 "B.Paste" user "Package Geometry/Pastemask Bottom")
		(5 "F.SilkS" user "Ref Des/Silkscreen Top")
		(7 "B.SilkS" user "Ref Des/Silkscreen Bottom")
		(1 "F.Mask" user "Board Geometry/Soldermask Top")
		(3 "B.Mask" user "Board Geometry/Soldermask Bottom")
		(17 "Dwgs.User" user "User.Drawings")
		(19 "Cmts.User" user "User.Comments")
		(21 "Eco1.User" user "User.Eco1")
		(23 "Eco2.User" user "User.Eco2")
		(25 "Edge.Cuts" user "Board Geometry/Outline")
		(27 "Margin" user)
		(31 "F.CrtYd" user "Package Geometry/Place Bound Top")
		(29 "B.CrtYd" user "Package Geometry/Place Bound Bottom")
		(35 "F.Fab" user "Ref Des/Assembly Top")
		(33 "B.Fab" user "Ref Des/Assembly Bottom")
	)
	(footprint ""
		(layer "B.Cu")
		(at 78.072488 -381.238252)
		(property "Reference" "C7025"
			(at 0 0 0)
			(layer "B.SilkS")
			(hide yes)
			(effects
				(font
					(size 1.27 1.27)
				)
				(justify mirror)
			)
		)
		(property "Value" ""
			(at 0 0 0)
			(layer "B.Fab")
			(effects
				(font
					(size 1.27 1.27)
				)
				(justify mirror)
			)
		)
		(duplicate_pad_numbers_are_jumpers no)
		(fp_line
			(start -1.524 -0.762)
			(end -1.524 0.762)
			(stroke
				(width 0.1524)
				(type default)
			)
			(layer "B.SilkS")
		)
		(fp_line
			(start -1.524 0.762)
			(end 1.524 0.762)
			(stroke
				(width 0.1524)
				(type default)
			)
			(layer "B.SilkS")
		)
		(fp_line
			(start 1.524 -0.762)
			(end -1.524 -0.762)
			(stroke
				(width 0.1524)
				(type default)
			)
			(layer "B.SilkS")
		)
		(fp_line
			(start 1.524 0.762)
			(end 1.524 -0.762)
			(stroke
				(width 0.1524)
				(type default)
			)
			(layer "B.SilkS")
		)
		(fp_line
			(start -1.1049 -0.724916)
			(end 1.1049 -0.724916)
			(stroke
				(width 0.1)
				(type default)
			)
			(layer "B.Fab")
		)
		(fp_line
			(start -1.1049 0.724916)
			(end -1.1049 -0.724916)
			(stroke
				(width 0.1)
				(type default)
			)
			(layer "B.Fab")
		)
		(fp_line
			(start 1.1049 -0.724916)
			(end 1.1049 0.724916)
			(stroke
				(width 0.1)
				(type default)
			)
			(layer "B.Fab")
		)
		(fp_line
			(start 1.1049 0.724916)
			(end -1.1049 0.724916)
			(stroke
				(width 0.1)
				(type default)
			)
			(layer "B.Fab")
		)
		(pad "1" smd rect
			(at 0.889 0)
			(size 1.016 1.27)
			(layers "B.Cu" "B.Mask" "B.Paste")
			(net "P0V9_CPU1_RT1_2A")
		)
		(pad "2" smd rect
			(at -0.889 0)
			(size 1.016 1.27)
			(layers "B.Cu" "B.Mask" "B.Paste")
			(net "GND")
		)
	)
	(footprint ""
		(layer "B.Cu")
		(at 398.563592 -341.172292 90)
		(property "Reference" "R934"
			(at 0 0 90)
			(layer "B.SilkS")
			(hide yes)
			(effects
				(font
					(size 1.27 1.27)
				)
				(justify mirror)
			)
		)
		(property "Value" ""
			(at 0 0 90)
			(layer "B.Fab")
			(effects
				(font
					(size 1.27 1.27)
				)
				(justify mirror)
			)
		)
		(duplicate_pad_numbers_are_jumpers no)
		(fp_line
			(start 0.7874 -0.4064)
			(end -0.7874 -0.4064)
			(stroke
				(width 0.1524)
				(type default)
			)
			(layer "B.SilkS")
		)
		(fp_line
			(start -0.7874 -0.4064)
			(end -0.7874 0.4064)
			(stroke
				(width 0.1524)
				(type default)
			)
			(layer "B.SilkS")
		)
		(fp_line
			(start 0.7874 0.4064)
			(end 0.7874 -0.4064)
			(stroke
				(width 0.1524)
				(type default)
			)
			(layer "B.SilkS")
		)
		(fp_line
			(start -0.7874 0.4064)
			(end 0.7874 0.4064)
			(stroke
				(width 0.1524)
				(type default)
			)
			(layer "B.SilkS")
		)
		(fp_line
			(start 0.67945 -0.305054)
			(end 0.12065 -0.305054)
			(stroke
				(width 0.1)
				(type default)
			)
			(layer "B.Fab")
		)
		(fp_line
			(start 0.12065 -0.305054)
			(end 0.12065 -0.2794)
			(stroke
				(width 0.1)
				(type default)
			)
			(layer "B.Fab")
		)
		(fp_line
			(start -0.12065 -0.3048)
			(end -0.67945 -0.3048)
			(stroke
				(width 0.1)
				(type default)
			)
			(layer "B.Fab")
		)
		(fp_line
			(start -0.67945 -0.3048)
			(end -0.67945 0.3048)
			(stroke
				(width 0.1)
				(type default)
			)
			(layer "B.Fab")
		)
		(fp_line
			(start 0.12065 -0.2794)
			(end -0.12065 -0.2794)
			(stroke
				(width 0.1)
				(type default)
			)
			(layer "B.Fab")
		)
		(fp_line
			(start -0.12065 -0.2794)
			(end -0.12065 -0.3048)
			(stroke
				(width 0.1)
				(type default)
			)
			(layer "B.Fab")
		)
		(fp_line
			(start 0.12065 0.2794)
			(end 0.12065 0.3048)
			(stroke
				(width 0.1)
				(type default)
			)
			(layer "B.Fab")
		)
		(fp_line
			(start -0.120396 0.2794)
			(end 0.12065 0.2794)
			(stroke
				(width 0.1)
				(type default)
			)
			(layer "B.Fab")
		)
		(fp_line
			(start 0.67945 0.3048)
			(end 0.67945 -0.305054)
			(stroke
				(width 0.1)
				(type default)
			)
			(layer "B.Fab")
		)
		(fp_line
			(start 0.12065 0.3048)
			(end 0.67945 0.3048)
			(stroke
				(width 0.1)
				(type default)
			)
			(layer "B.Fab")
		)
		(fp_line
			(start -0.120396 0.3048)
			(end -0.120396 0.2794)
			(stroke
				(width 0.1)
				(type default)
			)
			(layer "B.Fab")
		)
		(fp_line
			(start -0.67945 0.3048)
			(end -0.120396 0.3048)
			(stroke
				(width 0.1)
				(type default)
			)
			(layer "B.Fab")
		)
		(pad "1" smd circle
			(at 0.40005 0 270)
			(size 0 0)
			(layers "B.Cu" "B.Mask" "B.Paste")
			(net "FM_BIOS_POST_CMPLT_N")
		)
		(pad "2" smd circle
			(at -0.40005 0 270)
			(size 0 0)
			(layers "B.Cu" "B.Mask" "B.Paste")
			(net "BOOT_RDY_R1_N")
		)
	)
	(footprint ""
		(layer "B.Cu")
		(at 151.819102 -390.560052 90)
		(property "Reference" "C399"
			(at 0 0 90)
			(layer "B.SilkS")
			(hide yes)
			(effects
				(font
					(size 1.27 1.27)
				)
				(justify mirror)
			)
		)
		(property "Value" ""
			(at 0 0 90)
			(layer "B.Fab")
			(effects
				(font
					(size 1.27 1.27)
				)
				(justify mirror)
			)
		)
		(duplicate_pad_numbers_are_jumpers no)
		(fp_line
			(start 0.7874 -0.4064)
			(end -0.7874 -0.4064)
			(stroke
				(width 0.1524)
				(type default)
			)
			(layer "B.SilkS")
		)
		(fp_line
			(start -0.7874 -0.4064)
			(end -0.7874 0.4064)
			(stroke
				(width 0.1524)
				(type default)
			)
			(layer "B.SilkS")
		)
		(fp_line
			(start 0.7874 0.4064)
			(end 0.7874 -0.4064)
			(stroke
				(width 0.1524)
				(type default)
			)
			(layer "B.SilkS")
		)
		(fp_line
			(start -0.7874 0.4064)
			(end 0.7874 0.4064)
			(stroke
				(width 0.1524)
				(type default)
			)
			(layer "B.SilkS")
		)
		(fp_line
			(start 0.67945 -0.305054)
			(end 0.12065 -0.305054)
			(stroke
				(width 0.1)
				(type default)
			)
			(layer "B.Fab")
		)
		(fp_line
			(start 0.12065 -0.305054)
			(end 0.12065 -0.2794)
			(stroke
				(width 0.1)
				(type default)
			)
			(layer "B.Fab")
		)
		(fp_line
			(start -0.12065 -0.3048)
			(end -0.67945 -0.3048)
			(stroke
				(width 0.1)
				(type default)
			)
			(layer "B.Fab")
		)
		(fp_line
			(start -0.67945 -0.3048)
			(end -0.67945 0.3048)
			(stroke
				(width 0.1)
				(type default)
			)
			(layer "B.Fab")
		)
		(fp_line
			(start 0.12065 -0.2794)
			(end -0.12065 -0.2794)
			(stroke
				(width 0.1)
				(type default)
			)
			(layer "B.Fab")
		)
		(fp_line
			(start -0.12065 -0.2794)
			(end -0.12065 -0.3048)
			(stroke
				(width 0.1)
				(type default)
			)
			(layer "B.Fab")
		)
		(fp_line
			(start 0.12065 0.2794)
			(end 0.12065 0.3048)
			(stroke
				(width 0.1)
				(type default)
			)
			(layer "B.Fab")
		)
		(fp_line
			(start -0.120396 0.2794)
			(end 0.12065 0.2794)
			(stroke
				(width 0.1)
				(type default)
			)
			(layer "B.Fab")
		)
		(fp_line
			(start 0.67945 0.3048)
			(end 0.67945 -0.305054)
			(stroke
				(width 0.1)
				(type default)
			)
			(layer "B.Fab")
		)
		(fp_line
			(start 0.12065 0.3048)
			(end 0.67945 0.3048)
			(stroke
				(width 0.1)
				(type default)
			)
			(layer "B.Fab")
		)
		(fp_line
			(start -0.120396 0.3048)
			(end -0.120396 0.2794)
			(stroke
				(width 0.1)
				(type default)
			)
			(layer "B.Fab")
		)
		(fp_line
			(start -0.67945 0.3048)
			(end -0.120396 0.3048)
			(stroke
				(width 0.1)
				(type default)
			)
			(layer "B.Fab")
		)
		(pad "1" smd circle
			(at 0.40005 0 270)
			(size 0 0)
			(layers "B.Cu" "B.Mask" "B.Paste")
			(net "P0V9_CPU1_RT2_2A")
		)
		(pad "2" smd circle
			(at -0.40005 0 270)
			(size 0 0)
			(layers "B.Cu" "B.Mask" "B.Paste")
			(net "GND")
		)
	)
)
